(kicad_pcb
	(version 20260206)
	(generator "pcbnew")
	(generator_version "10.0")
	(general
		(thickness 1.6)
		(legacy_teardrops no)
	)
	(paper "A4")
	(title_block
		(title "01162023_DA0F0TEBIF0_F0T_Expander_BD_F_brd_V02_OCP.brd")
		(comment 1 "Grand Teton / footprints 6550-6555 of 9728")
	)
	(layers
		(0 "F.Cu" signal "TOP")
		(4 "In1.Cu" signal "GND")
		(6 "In2.Cu" signal "VCC")
		(8 "In3.Cu" signal "VCC1")
		(10 "In4.Cu" signal "GND1")
		(12 "In5.Cu" signal "IN1")
		(14 "In6.Cu" signal "GND2")
		(16 "In7.Cu" signal "IN2")
		(18 "In8.Cu" signal "GND3")
		(20 "In9.Cu" signal "IN3")
		(22 "In10.Cu" signal "GND4")
		(24 "In11.Cu" signal "IN4")
		(26 "In12.Cu" signal "GND5")
		(28 "In13.Cu" signal "IN5")
		(30 "In14.Cu" signal "GND6")
		(32 "In15.Cu" signal "IN6")
		(34 "In16.Cu" signal "GND7")
		(2 "B.Cu" signal "BOTTOM")
		(9 "F.Adhes" user "F.Adhesive")
		(11 "B.Adhes" user "B.Adhesive")
		(13 "F.Paste" user "Package Geometry/Pastemask Top")
		(15 "B.Paste" user "Package Geometry/Pastemask Bottom")
		(5 "F.SilkS" user "Ref Des/Silkscreen Top")
		(7 "B.SilkS" user "Ref Des/Silkscreen Bottom")
		(1 "F.Mask" user "Board Geometry/Soldermask Top")
		(3 "B.Mask" user "Board Geometry/Soldermask Bottom")
		(17 "Dwgs.User" user "User.Drawings")
		(19 "Cmts.User" user "User.Comments")
		(21 "Eco1.User" user "User.Eco1")
		(23 "Eco2.User" user "User.Eco2")
		(25 "Edge.Cuts" user "Board Geometry/Outline")
		(27 "Margin" user)
		(31 "F.CrtYd" user "Package Geometry/Place Bound Top")
		(29 "B.CrtYd" user "Package Geometry/Place Bound Bottom")
		(35 "F.Fab" user "Ref Des/Assembly Top")
		(33 "B.Fab" user "Ref Des/Assembly Bottom")
	)
	(footprint ""
		(layer "F.Cu")
		(at 293.69385 -165.670484 -90)
		(property "Reference" "R2467"
			(at 0 0 270)
			(layer "F.SilkS")
			(hide yes)
			(effects
				(font
					(size 1.27 1.27)
				)
			)
		)
		(property "Value" ""
			(at 0 0 270)
			(layer "F.Fab")
			(effects
				(font
					(size 1.27 1.27)
				)
			)
		)
		(duplicate_pad_numbers_are_jumpers no)
		(fp_line
			(start -0.7874 0.4064)
			(end -0.7874 -0.4064)
			(stroke
				(width 0.1524)
				(type default)
			)
			(layer "F.SilkS")
		)
		(fp_line
			(start 0.7874 0.4064)
			(end -0.7874 0.4064)
			(stroke
				(width 0.1524)
				(type default)
			)
			(layer "F.SilkS")
		)
		(fp_line
			(start -0.7874 -0.4064)
			(end 0.7874 -0.4064)
			(stroke
				(width 0.1524)
				(type default)
			)
			(layer "F.SilkS")
		)
		(fp_line
			(start 0.7874 -0.4064)
			(end 0.7874 0.4064)
			(stroke
				(width 0.1524)
				(type default)
			)
			(layer "F.SilkS")
		)
		(fp_line
			(start -0.67945 0.3048)
			(end -0.67945 -0.305054)
			(stroke
				(width 0.1)
				(type default)
			)
			(layer "F.Fab")
		)
		(fp_line
			(start -0.12065 0.3048)
			(end -0.67945 0.3048)
			(stroke
				(width 0.1)
				(type default)
			)
			(layer "F.Fab")
		)
		(fp_line
			(start 0.120396 0.3048)
			(end 0.120396 0.2794)
			(stroke
				(width 0.1)
				(type default)
			)
			(layer "F.Fab")
		)
		(fp_line
			(start 0.67945 0.3048)
			(end 0.120396 0.3048)
			(stroke
				(width 0.1)
				(type default)
			)
			(layer "F.Fab")
		)
		(fp_line
			(start -0.12065 0.2794)
			(end -0.12065 0.3048)
			(stroke
				(width 0.1)
				(type default)
			)
			(layer "F.Fab")
		)
		(fp_line
			(start 0.120396 0.2794)
			(end -0.12065 0.2794)
			(stroke
				(width 0.1)
				(type default)
			)
			(layer "F.Fab")
		)
		(fp_line
			(start -0.12065 -0.2794)
			(end 0.12065 -0.2794)
			(stroke
				(width 0.1)
				(type default)
			)
			(layer "F.Fab")
		)
		(fp_line
			(start 0.12065 -0.2794)
			(end 0.12065 -0.3048)
			(stroke
				(width 0.1)
				(type default)
			)
			(layer "F.Fab")
		)
		(fp_line
			(start 0.12065 -0.3048)
			(end 0.67945 -0.3048)
			(stroke
				(width 0.1)
				(type default)
			)
			(layer "F.Fab")
		)
		(fp_line
			(start 0.67945 -0.3048)
			(end 0.67945 0.3048)
			(stroke
				(width 0.1)
				(type default)
			)
			(layer "F.Fab")
		)
		(fp_line
			(start -0.67945 -0.305054)
			(end -0.12065 -0.305054)
			(stroke
				(width 0.1)
				(type default)
			)
			(layer "F.Fab")
		)
		(fp_line
			(start -0.12065 -0.305054)
			(end -0.12065 -0.2794)
			(stroke
				(width 0.1)
				(type default)
			)
			(layer "F.Fab")
		)
		(pad "1" smd circle
			(at -0.40005 0 270)
			(size 0 0)
			(layers "F.Cu" "F.Mask" "F.Paste")
			(net "P3V3_NIC4")
		)
		(pad "2" smd circle
			(at 0.40005 0 270)
			(size 0 0)
			(layers "F.Cu" "F.Mask" "F.Paste")
			(net "NIC4_PWRBRK_N")
		)
	)
	(footprint ""
		(layer "F.Cu")
		(at 442.794136 -116.410486)
		(property "Reference" "PR7105"
			(at 0 0 0)
			(layer "F.SilkS")
			(hide yes)
			(effects
				(font
					(size 1.27 1.27)
				)
			)
		)
		(property "Value" ""
			(at 0 0 0)
			(layer "F.Fab")
			(effects
				(font
					(size 1.27 1.27)
				)
			)
		)
		(duplicate_pad_numbers_are_jumpers no)
		(fp_line
			(start -0.7874 -0.4064)
			(end 0.7874 -0.4064)
			(stroke
				(width 0.1524)
				(type default)
			)
			(layer "F.SilkS")
		)
		(fp_line
			(start -0.7874 0.4064)
			(end -0.7874 -0.4064)
			(stroke
				(width 0.1524)
				(type default)
			)
			(layer "F.SilkS")
		)
		(fp_line
			(start 0.7874 -0.4064)
			(end 0.7874 0.4064)
			(stroke
				(width 0.1524)
				(type default)
			)
			(layer "F.SilkS")
		)
		(fp_line
			(start 0.7874 0.4064)
			(end -0.7874 0.4064)
			(stroke
				(width 0.1524)
				(type default)
			)
			(layer "F.SilkS")
		)
		(fp_line
			(start -0.67945 -0.305054)
			(end -0.12065 -0.305054)
			(stroke
				(width 0.1)
				(type default)
			)
			(layer "F.Fab")
		)
		(fp_line
			(start -0.67945 0.3048)
			(end -0.67945 -0.305054)
			(stroke
				(width 0.1)
				(type default)
			)
			(layer "F.Fab")
		)
		(fp_line
			(start -0.12065 -0.305054)
			(end -0.12065 -0.2794)
			(stroke
				(width 0.1)
				(type default)
			)
			(layer "F.Fab")
		)
		(fp_line
			(start -0.12065 -0.2794)
			(end 0.12065 -0.2794)
			(stroke
				(width 0.1)
				(type default)
			)
			(layer "F.Fab")
		)
		(fp_line
			(start -0.12065 0.2794)
			(end -0.12065 0.3048)
			(stroke
				(width 0.1)
				(type default)
			)
			(layer "F.Fab")
		)
		(fp_line
			(start -0.12065 0.3048)
			(end -0.67945 0.3048)
			(stroke
				(width 0.1)
				(type default)
			)
			(layer "F.Fab")
		)
		(fp_line
			(start 0.120396 0.2794)
			(end -0.12065 0.2794)
			(stroke
				(width 0.1)
				(type default)
			)
			(layer "F.Fab")
		)
		(fp_line
			(start 0.120396 0.3048)
			(end 0.120396 0.2794)
			(stroke
				(width 0.1)
				(type default)
			)
			(layer "F.Fab")
		)
		(fp_line
			(start 0.12065 -0.3048)
			(end 0.67945 -0.3048)
			(stroke
				(width 0.1)
				(type default)
			)
			(layer "F.Fab")
		)
		(fp_line
			(start 0.12065 -0.2794)
			(end 0.12065 -0.3048)
			(stroke
				(width 0.1)
				(type default)
			)
			(layer "F.Fab")
		)
		(fp_line
			(start 0.67945 -0.3048)
			(end 0.67945 0.3048)
			(stroke
				(width 0.1)
				(type default)
			)
			(layer "F.Fab")
		)
		(fp_line
			(start 0.67945 0.3048)
			(end 0.120396 0.3048)
			(stroke
				(width 0.1)
				(type default)
			)
			(layer "F.Fab")
		)
		(pad "1" smd circle
			(at -0.40005 0)
			(size 0 0)
			(layers "F.Cu" "F.Mask" "F.Paste")
			(net "P3V3_NIC7_CO_MODE")
		)
		(pad "2" smd circle
			(at 0.40005 0)
			(size 0 0)
			(layers "F.Cu" "F.Mask" "F.Paste")
			(net "GND")
		)
	)
	(footprint ""
		(layer "F.Cu")
		(at 365.24692 -261.606538 90)
		(property "Reference" "C3657"
			(at 0 0 90)
			(layer "F.SilkS")
			(hide yes)
			(effects
				(font
					(size 1.27 1.27)
				)
			)
		)
		(property "Value" ""
			(at 0 0 90)
			(layer "F.Fab")
			(effects
				(font
					(size 1.27 1.27)
				)
			)
		)
		(duplicate_pad_numbers_are_jumpers no)
		(fp_line
			(start 0.7874 -0.4064)
			(end 0.7874 0.4064)
			(stroke
				(width 0.1524)
				(type default)
			)
			(layer "F.SilkS")
		)
		(fp_line
			(start -0.7874 -0.4064)
			(end 0.7874 -0.4064)
			(stroke
				(width 0.1524)
				(type default)
			)
			(layer "F.SilkS")
		)
		(fp_line
			(start 0.7874 0.4064)
			(end -0.7874 0.4064)
			(stroke
				(width 0.1524)
				(type default)
			)
			(layer "F.SilkS")
		)
		(fp_line
			(start -0.7874 0.4064)
			(end -0.7874 -0.4064)
			(stroke
				(width 0.1524)
				(type default)
			)
			(layer "F.SilkS")
		)
		(fp_line
			(start -0.12065 -0.305054)
			(end -0.12065 -0.2794)
			(stroke
				(width 0.1)
				(type default)
			)
			(layer "F.Fab")
		)
		(fp_line
			(start -0.67945 -0.305054)
			(end -0.12065 -0.305054)
			(stroke
				(width 0.1)
				(type default)
			)
			(layer "F.Fab")
		)
		(fp_line
			(start 0.67945 -0.3048)
			(end 0.67945 0.3048)
			(stroke
				(width 0.1)
				(type default)
			)
			(layer "F.Fab")
		)
		(fp_line
			(start 0.12065 -0.3048)
			(end 0.67945 -0.3048)
			(stroke
				(width 0.1)
				(type default)
			)
			(layer "F.Fab")
		)
		(fp_line
			(start 0.12065 -0.2794)
			(end 0.12065 -0.3048)
			(stroke
				(width 0.1)
				(type default)
			)
			(layer "F.Fab")
		)
		(fp_line
			(start -0.12065 -0.2794)
			(end 0.12065 -0.2794)
			(stroke
				(width 0.1)
				(type default)
			)
			(layer "F.Fab")
		)
		(fp_line
			(start 0.120396 0.2794)
			(end -0.12065 0.2794)
			(stroke
				(width 0.1)
				(type default)
			)
			(layer "F.Fab")
		)
		(fp_line
			(start -0.12065 0.2794)
			(end -0.12065 0.3048)
			(stroke
				(width 0.1)
				(type default)
			)
			(layer "F.Fab")
		)
		(fp_line
			(start 0.67945 0.3048)
			(end 0.120396 0.3048)
			(stroke
				(width 0.1)
				(type default)
			)
			(layer "F.Fab")
		)
		(fp_line
			(start 0.120396 0.3048)
			(end 0.120396 0.2794)
			(stroke
				(width 0.1)
				(type default)
			)
			(layer "F.Fab")
		)
		(fp_line
			(start -0.12065 0.3048)
			(end -0.67945 0.3048)
			(stroke
				(width 0.1)
				(type default)
			)
			(layer "F.Fab")
		)
		(fp_line
			(start -0.67945 0.3048)
			(end -0.67945 -0.305054)
			(stroke
				(width 0.1)
				(type default)
			)
			(layer "F.Fab")
		)
		(pad "1" smd circle
			(at -0.40005 0 90)
			(size 0 0)
			(layers "F.Cu" "F.Mask" "F.Paste")
			(net "P3V3_AUX")
		)
		(pad "2" smd circle
			(at 0.40005 0 90)
			(size 0 0)
			(layers "F.Cu" "F.Mask" "F.Paste")
			(net "GND")
		)
	)
	(footprint ""
		(layer "F.Cu")
		(at 345.934792 -240.691162 -90)
		(property "Reference" "R3540"
			(at 0 0 270)
			(layer "F.SilkS")
			(hide yes)
			(effects
				(font
					(size 1.27 1.27)
				)
			)
		)
		(property "Value" ""
			(at 0 0 270)
			(layer "F.Fab")
			(effects
				(font
					(size 1.27 1.27)
				)
			)
		)
		(duplicate_pad_numbers_are_jumpers no)
		(fp_line
			(start -0.7874 0.4064)
			(end -0.7874 -0.4064)
			(stroke
				(width 0.1524)
				(type default)
			)
			(layer "F.SilkS")
		)
		(fp_line
			(start 0.7874 0.4064)
			(end -0.7874 0.4064)
			(stroke
				(width 0.1524)
				(type default)
			)
			(layer "F.SilkS")
		)
		(fp_line
			(start -0.7874 -0.4064)
			(end 0.7874 -0.4064)
			(stroke
				(width 0.1524)
				(type default)
			)
			(layer "F.SilkS")
		)
		(fp_line
			(start 0.7874 -0.4064)
			(end 0.7874 0.4064)
			(stroke
				(width 0.1524)
				(type default)
			)
			(layer "F.SilkS")
		)
		(fp_line
			(start -0.67945 0.3048)
			(end -0.67945 -0.305054)
			(stroke
				(width 0.1)
				(type default)
			)
			(layer "F.Fab")
		)
		(fp_line
			(start -0.12065 0.3048)
			(end -0.67945 0.3048)
			(stroke
				(width 0.1)
				(type default)
			)
			(layer "F.Fab")
		)
		(fp_line
			(start 0.120396 0.3048)
			(end 0.120396 0.2794)
			(stroke
				(width 0.1)
				(type default)
			)
			(layer "F.Fab")
		)
		(fp_line
			(start 0.67945 0.3048)
			(end 0.120396 0.3048)
			(stroke
				(width 0.1)
				(type default)
			)
			(layer "F.Fab")
		)
		(fp_line
			(start -0.12065 0.2794)
			(end -0.12065 0.3048)
			(stroke
				(width 0.1)
				(type default)
			)
			(layer "F.Fab")
		)
		(fp_line
			(start 0.120396 0.2794)
			(end -0.12065 0.2794)
			(stroke
				(width 0.1)
				(type default)
			)
			(layer "F.Fab")
		)
		(fp_line
			(start -0.12065 -0.2794)
			(end 0.12065 -0.2794)
			(stroke
				(width 0.1)
				(type default)
			)
			(layer "F.Fab")
		)
		(fp_line
			(start 0.12065 -0.2794)
			(end 0.12065 -0.3048)
			(stroke
				(width 0.1)
				(type default)
			)
			(layer "F.Fab")
		)
		(fp_line
			(start 0.12065 -0.3048)
			(end 0.67945 -0.3048)
			(stroke
				(width 0.1)
				(type default)
			)
			(layer "F.Fab")
		)
		(fp_line
			(start 0.67945 -0.3048)
			(end 0.67945 0.3048)
			(stroke
				(width 0.1)
				(type default)
			)
			(layer "F.Fab")
		)
		(fp_line
			(start -0.67945 -0.305054)
			(end -0.12065 -0.305054)
			(stroke
				(width 0.1)
				(type default)
			)
			(layer "F.Fab")
		)
		(fp_line
			(start -0.12065 -0.305054)
			(end -0.12065 -0.2794)
			(stroke
				(width 0.1)
				(type default)
			)
			(layer "F.Fab")
		)
		(pad "1" smd circle
			(at -0.40005 0 270)
			(size 0 0)
			(layers "F.Cu" "F.Mask" "F.Paste")
			(net "SMB_FPGA_ALERT_R_N")
		)
		(pad "2" smd circle
			(at 0.40005 0 270)
			(size 0 0)
			(layers "F.Cu" "F.Mask" "F.Paste")
			(net "SMB_FPGA_ALERT_N")
		)
	)
	(footprint ""
		(layer "F.Cu")
		(at 88.835992 -289.230816 90)
		(property "Reference" "R3892"
			(at 0 0 90)
			(layer "F.SilkS")
			(hide yes)
			(effects
				(font
					(size 1.27 1.27)
				)
			)
		)
		(property "Value" ""
			(at 0 0 90)
			(layer "F.Fab")
			(effects
				(font
					(size 1.27 1.27)
				)
			)
		)
		(duplicate_pad_numbers_are_jumpers no)
		(fp_line
			(start 0.7874 -0.4064)
			(end 0.7874 0.4064)
			(stroke
				(width 0.1524)
				(type default)
			)
			(layer "F.SilkS")
		)
		(fp_line
			(start -0.7874 -0.4064)
			(end 0.7874 -0.4064)
			(stroke
				(width 0.1524)
				(type default)
			)
			(layer "F.SilkS")
		)
		(fp_line
			(start 0.7874 0.4064)
			(end -0.7874 0.4064)
			(stroke
				(width 0.1524)
				(type default)
			)
			(layer "F.SilkS")
		)
		(fp_line
			(start -0.7874 0.4064)
			(end -0.7874 -0.4064)
			(stroke
				(width 0.1524)
				(type default)
			)
			(layer "F.SilkS")
		)
		(fp_line
			(start -0.12065 -0.305054)
			(end -0.12065 -0.2794)
			(stroke
				(width 0.1)
				(type default)
			)
			(layer "F.Fab")
		)
		(fp_line
			(start -0.67945 -0.305054)
			(end -0.12065 -0.305054)
			(stroke
				(width 0.1)
				(type default)
			)
			(layer "F.Fab")
		)
		(fp_line
			(start 0.67945 -0.3048)
			(end 0.67945 0.3048)
			(stroke
				(width 0.1)
				(type default)
			)
			(layer "F.Fab")
		)
		(fp_line
			(start 0.12065 -0.3048)
			(end 0.67945 -0.3048)
			(stroke
				(width 0.1)
				(type default)
			)
			(layer "F.Fab")
		)
		(fp_line
			(start 0.12065 -0.2794)
			(end 0.12065 -0.3048)
			(stroke
				(width 0.1)
				(type default)
			)
			(layer "F.Fab")
		)
		(fp_line
			(start -0.12065 -0.2794)
			(end 0.12065 -0.2794)
			(stroke
				(width 0.1)
				(type default)
			)
			(layer "F.Fab")
		)
		(fp_line
			(start 0.120396 0.2794)
			(end -0.12065 0.2794)
			(stroke
				(width 0.1)
				(type default)
			)
			(layer "F.Fab")
		)
		(fp_line
			(start -0.12065 0.2794)
			(end -0.12065 0.3048)
			(stroke
				(width 0.1)
				(type default)
			)
			(layer "F.Fab")
		)
		(fp_line
			(start 0.67945 0.3048)
			(end 0.120396 0.3048)
			(stroke
				(width 0.1)
				(type default)
			)
			(layer "F.Fab")
		)
		(fp_line
			(start 0.120396 0.3048)
			(end 0.120396 0.2794)
			(stroke
				(width 0.1)
				(type default)
			)
			(layer "F.Fab")
		)
		(fp_line
			(start -0.12065 0.3048)
			(end -0.67945 0.3048)
			(stroke
				(width 0.1)
				(type default)
			)
			(layer "F.Fab")
		)
		(fp_line
			(start -0.67945 0.3048)
			(end -0.67945 -0.305054)
			(stroke
				(width 0.1)
				(type default)
			)
			(layer "F.Fab")
		)
		(pad "1" smd circle
			(at -0.40005 0 90)
			(size 0 0)
			(layers "F.Cu" "F.Mask" "F.Paste")
			(net "SMB_PEX0_FPGA_SDA")
		)
		(pad "2" smd circle
			(at 0.40005 0 90)
			(size 0 0)
			(layers "F.Cu" "F.Mask" "F.Paste")
			(net "SMB_PEX0_HOST_LS_SDA")
		)
	)
	(footprint ""
		(layer "F.Cu")
		(at 265.487658 -285.218632)
		(property "Reference" "C3406"
			(at 0 0 0)
			(layer "F.SilkS")
			(hide yes)
			(effects
				(font
					(size 1.27 1.27)
				)
			)
		)
		(property "Value" ""
			(at 0 0 0)
			(layer "F.Fab")
			(effects
				(font
					(size 1.27 1.27)
				)
			)
		)
		(duplicate_pad_numbers_are_jumpers no)
		(fp_line
			(start -1.2954 -0.5842)
			(end 1.2954 -0.5842)
			(stroke
				(width 0.1524)
				(type default)
			)
			(layer "F.SilkS")
		)
		(fp_line
			(start -1.2954 0.5842)
			(end -1.2954 -0.5842)
			(stroke
				(width 0.1524)
				(type default)
			)
			(layer "F.SilkS")
		)
		(fp_line
			(start 1.2954 -0.5842)
			(end 1.2954 0.5842)
			(stroke
				(width 0.1524)
				(type default)
			)
			(layer "F.SilkS")
		)
		(fp_line
			(start 1.2954 0.5842)
			(end -1.2954 0.5842)
			(stroke
				(width 0.1524)
				(type default)
			)
			(layer "F.SilkS")
		)
		(fp_line
			(start -1.1938 -0.4064)
			(end -0.8636 -0.4064)
			(stroke
				(width 0.1)
				(type default)
			)
			(layer "F.Fab")
		)
		(fp_line
			(start -1.1938 0.4064)
			(end -1.1938 -0.4064)
			(stroke
				(width 0.1)
				(type default)
			)
			(layer "F.Fab")
		)
		(fp_line
			(start -0.8636 -0.4572)
			(end 0.8636 -0.4572)
			(stroke
				(width 0.1)
				(type default)
			)
			(layer "F.Fab")
		)
		(fp_line
			(start -0.8636 -0.4064)
			(end -0.8636 -0.4572)
			(stroke
				(width 0.1)
				(type default)
			)
			(layer "F.Fab")
		)
		(fp_line
			(start -0.8636 0.4064)
			(end -1.1938 0.4064)
			(stroke
				(width 0.1)
				(type default)
			)
			(layer "F.Fab")
		)
		(fp_line
			(start -0.8636 0.4572)
			(end -0.8636 0.4064)
			(stroke
				(width 0.1)
				(type default)
			)
			(layer "F.Fab")
		)
		(fp_line
			(start 0.8636 -0.4572)
			(end 0.8636 -0.4064)
			(stroke
				(width 0.1)
				(type default)
			)
			(layer "F.Fab")
		)
		(fp_line
			(start 0.8636 -0.4064)
			(end 1.1938 -0.4064)
			(stroke
				(width 0.1)
				(type default)
			)
			(layer "F.Fab")
		)
		(fp_line
			(start 0.8636 0.4064)
			(end 0.8636 0.4572)
			(stroke
				(width 0.1)
				(type default)
			)
			(layer "F.Fab")
		)
		(fp_line
			(start 0.8636 0.4572)
			(end -0.8636 0.4572)
			(stroke
				(width 0.1)
				(type default)
			)
			(layer "F.Fab")
		)
		(fp_line
			(start 1.1938 -0.4064)
			(end 1.1938 0.4064)
			(stroke
				(width 0.1)
				(type default)
			)
			(layer "F.Fab")
		)
		(fp_line
			(start 1.1938 0.4064)
			(end 0.8636 0.4064)
			(stroke
				(width 0.1)
				(type default)
			)
			(layer "F.Fab")
		)
		(pad "1" smd rect
			(at -0.7366 0 270)
			(size 0.7112 0.8128)
			(layers "F.Cu" "F.Mask" "F.Paste")
			(net "PCEPLL7_VDDA18_PEX2")
		)
		(pad "2" smd rect
			(at 0.7366 0 270)
			(size 0.7112 0.8128)
			(layers "F.Cu" "F.Mask" "F.Paste")
			(net "GND")
		)
	)
)
